(kicad_pcb
	(version 20241229)
	(generator "pcbnew")
	(generator_version "9.0")
	(general
		(thickness 1.6296)
		(legacy_teardrops no)
	)
	(paper "A3")
	(title_block
		(title "Thunderbolt to 10GbE adapter")
		(date "2026-04-21")
		(rev "1.1.0")
		(company "Antmicro Ltd")
		(comment 1 "www.antmicro.com")
		(comment 9 "footprints 360-364 of 703")
	)
	(layers
		(0 "F.Cu" signal)
		(4 "In1.Cu" signal)
		(6 "In2.Cu" signal)
		(8 "In3.Cu" signal)
		(10 "In4.Cu" signal)
		(12 "In5.Cu" signal)
		(14 "In6.Cu" signal)
		(2 "B.Cu" signal)
		(9 "F.Adhes" user "F.Adhesive")
		(11 "B.Adhes" user "B.Adhesive")
		(13 "F.Paste" user)
		(15 "B.Paste" user)
		(5 "F.SilkS" user "F.Silkscreen")
		(7 "B.SilkS" user "B.Silkscreen")
		(1 "F.Mask" user)
		(3 "B.Mask" user)
		(17 "Dwgs.User" user "User.Drawings")
		(19 "Cmts.User" user "User.Comments")
		(21 "Eco1.User" user "User.Eco1")
		(23 "Eco2.User" user "User.Eco2")
		(25 "Edge.Cuts" user)
		(27 "Margin" user)
		(31 "F.CrtYd" user "F.Courtyard")
		(29 "B.CrtYd" user "B.Courtyard")
		(35 "F.Fab" user)
		(33 "B.Fab" user)
	)
	(footprint "antmicro-footprints:C_0603_1608Metric"
		(layer "F.Cu")
		(at 141.5 122.95 90)
		(descr "Capacitor SMD 0603")
		(tags "capacitor 0603")
		(property "Reference" "C89"
			(at -2.15 1.6 90)
			(layer "F.SilkS")
			(effects
				(font
					(size 0.7 0.7)
					(thickness 0.15)
				)
				(justify left bottom)
			)
		)
		(property "Value" "C_22u_0603"
			(at -1.42757 1.770288 90)
			(layer "F.Fab")
			(effects
				(font
					(size 0.7 0.7)
					(thickness 0.15)
				)
				(justify left bottom)
			)
		)
		(property "Datasheet" "https://www.murata.com/products/productdetail?partno=GRM188R60J226MEA0%23"
			(at 0 0 90)
			(layer "F.Fab")
			(hide yes)
			(effects
				(font
					(size 1.27 1.27)
					(thickness 0.15)
				)
			)
		)
		(property "Description" "SMD Multilayer Ceramic Capacitor, 22 µF, 6.3 V, 0603 [1608 Metric], ± 20%, X5R, GRM Series"
			(at 0 0 90)
			(layer "F.Fab")
			(hide yes)
			(effects
				(font
					(size 1.27 1.27)
					(thickness 0.15)
				)
			)
		)
		(property "MPN" "GRM188R60J226MEA0D"
			(at 0 0 90)
			(unlocked yes)
			(layer "F.Fab")
			(hide yes)
			(effects
				(font
					(size 1 1)
					(thickness 0.15)
				)
			)
		)
		(property "Manufacturer" "Murata"
			(at 0 0 90)
			(unlocked yes)
			(layer "F.Fab")
			(hide yes)
			(effects
				(font
					(size 1 1)
					(thickness 0.15)
				)
			)
		)
		(property "License" "Apache-2.0"
			(at 0 0 90)
			(unlocked yes)
			(layer "F.Fab")
			(hide yes)
			(effects
				(font
					(size 1 1)
					(thickness 0.15)
				)
			)
		)
		(property "Val" "22u"
			(at 0 0 90)
			(unlocked yes)
			(layer "F.Fab")
			(hide yes)
			(effects
				(font
					(size 1 1)
					(thickness 0.15)
				)
			)
		)
		(property "Voltage" ""
			(at 0 0 90)
			(unlocked yes)
			(layer "F.Fab")
			(hide yes)
			(effects
				(font
					(size 1 1)
					(thickness 0.15)
				)
			)
		)
		(property "Dielectric" ""
			(at 0 0 90)
			(unlocked yes)
			(layer "F.Fab")
			(hide yes)
			(effects
				(font
					(size 1 1)
					(thickness 0.15)
				)
			)
		)
		(property "Author" "Antmicro"
			(at 0 0 90)
			(unlocked yes)
			(layer "F.Fab")
			(hide yes)
			(effects
				(font
					(size 1 1)
					(thickness 0.15)
				)
			)
		)
		(sheetname "/TB Controller - Power/")
		(sheetfile "tb-power.kicad_sch")
		(attr smd)
		(fp_line
			(start -0.15 -0.4)
			(end 0.15 -0.4)
			(stroke
				(width 0.15)
				(type solid)
			)
			(layer "F.SilkS")
		)
		(fp_line
			(start -0.15 0.4)
			(end 0.15 0.4)
			(stroke
				(width 0.15)
				(type solid)
			)
			(layer "F.SilkS")
		)
		(fp_rect
			(start -1.25 -0.65)
			(end 1.25 0.65)
			(stroke
				(width 0.05)
				(type solid)
			)
			(fill no)
			(layer "F.CrtYd")
		)
		(fp_rect
			(start -0.8 -0.4)
			(end 0.8 0.4)
			(stroke
				(width 0.15)
				(type solid)
			)
			(fill no)
			(layer "F.Fab")
		)
		(fp_text user "License: Apache-2.0"
			(at -1.682 5.895 90)
			(layer "F.Fab")
			(effects
				(font
					(size 0.7 0.7)
					(thickness 0.15)
				)
				(justify left bottom)
			)
		)
		(fp_text user "${REFERENCE}"
			(at -1.682 3.895 90)
			(layer "F.Fab")
			(effects
				(font
					(size 0.7 0.7)
					(thickness 0.15)
				)
				(justify left bottom)
			)
		)
		(fp_text user "Author: Antmicro"
			(at -1.682 4.894 90)
			(layer "F.Fab")
			(effects
				(font
					(size 0.7 0.7)
					(thickness 0.15)
				)
				(justify left bottom)
			)
		)
		(pad "1" smd roundrect
			(at -0.7 0 90)
			(size 0.8 1)
			(layers "F.Cu" "F.Mask" "F.Paste")
			(roundrect_rratio 0.2)
			(net 23 "GND")
			(pintype "passive")
		)
		(pad "2" smd roundrect
			(at 0.7 0 90)
			(size 0.8 1)
			(layers "F.Cu" "F.Mask" "F.Paste")
			(roundrect_rratio 0.2)
			(net 68 "/TB Controller - Power/VCC_0P9")
			(pintype "passive")
		)
	)
	(footprint "antmicro-footprints:MP_Pad6mm_Drill3.2mm"
		(layer "F.Cu")
		(at 172 108.000001 90)
		(property "Reference" "MP7"
			(at 3.400001 -1.2 180)
			(layer "F.SilkS")
			(effects
				(font
					(size 0.7 0.7)
					(thickness 0.15)
				)
				(justify left bottom)
			)
		)
		(property "Value" "MP_Pad6mm_Drill3.2mm"
			(at 0 3.9 90)
			(layer "F.Fab")
			(effects
				(font
					(size 0.7 0.7)
					(thickness 0.15)
				)
				(justify left bottom)
			)
		)
		(property "Description" "Mechanical part"
			(at 0 0 90)
			(layer "F.Fab")
			(hide yes)
			(effects
				(font
					(size 1.27 1.27)
					(thickness 0.15)
				)
			)
		)
		(property "Author" "Antmicro"
			(at 0 0 90)
			(unlocked yes)
			(layer "F.Fab")
			(hide yes)
			(effects
				(font
					(size 1 1)
					(thickness 0.15)
				)
			)
		)
		(property "License" "Apache-2.0"
			(at 0 0 90)
			(unlocked yes)
			(layer "F.Fab")
			(hide yes)
			(effects
				(font
					(size 1 1)
					(thickness 0.15)
				)
			)
		)
		(sheetname "/")
		(sheetfile "thunderbolt-to-10gbe-adapter.kicad_sch")
		(attr exclude_from_pos_files exclude_from_bom)
		(fp_circle
			(center 0 0)
			(end 3.25 0)
			(stroke
				(width 0.05)
				(type default)
			)
			(fill no)
			(layer "F.CrtYd")
		)
		(fp_text user "${REFERENCE}"
			(at -0.178 6.025 90)
			(layer "F.Fab")
			(effects
				(font
					(size 0.7 0.7)
					(thickness 0.15)
				)
				(justify left bottom)
			)
		)
		(fp_text user "License: Apache-2.0"
			(at -0.178 8.425 90)
			(layer "F.Fab")
			(effects
				(font
					(size 0.7 0.7)
					(thickness 0.15)
				)
				(justify left bottom)
			)
		)
		(fp_text user "Author: Antmicro"
			(at -0.178 7.225 90)
			(layer "F.Fab")
			(effects
				(font
					(size 0.7 0.7)
					(thickness 0.15)
				)
				(justify left bottom)
			)
		)
		(pad "1" thru_hole circle
			(at 0 0 90)
			(size 6 6)
			(drill 3.2)
			(layers "*.Cu" "*.Mask")
			(remove_unused_layers no)
			(net 23 "GND")
			(pintype "passive")
		)
	)
	(footprint "antmicro-footprints:C_0402_1005Metric"
		(layer "F.Cu")
		(at 135.85 129.150004 -90)
		(descr "Capacitor SMD 0402")
		(tags "capacitor SMD 0402")
		(property "Reference" "C98"
			(at -0.450004 -7.15 270)
			(layer "F.SilkS")
			(effects
				(font
					(size 0.7 0.7)
					(thickness 0.15)
				)
				(justify left bottom)
			)
		)
		(property "Value" "C_10u_0402"
			(at -1.022927 2.155213 270)
			(layer "F.Fab")
			(effects
				(font
					(size 0.7 0.7)
					(thickness 0.15)
				)
				(justify left bottom)
			)
		)
		(property "Datasheet" "https://www.yageo.com/en/Chart/Download/pdf/CC0402MRX5R5BB106"
			(at 0 0 270)
			(layer "F.Fab")
			(hide yes)
			(effects
				(font
					(size 1.27 1.27)
					(thickness 0.15)
				)
			)
		)
		(property "Description" "SMD Multilayer Ceramic Capacitor, 10 µF, 6.3 V, 0402 [1005 Metric], ± 20%, X5R, CC Series"
			(at 0 0 270)
			(layer "F.Fab")
			(hide yes)
			(effects
				(font
					(size 1.27 1.27)
					(thickness 0.15)
				)
			)
		)
		(property "MPN" "CC0402MRX5R5BB106"
			(at 0 0 270)
			(unlocked yes)
			(layer "F.Fab")
			(hide yes)
			(effects
				(font
					(size 1 1)
					(thickness 0.15)
				)
			)
		)
		(property "Manufacturer" "YAGEO"
			(at 0 0 270)
			(unlocked yes)
			(layer "F.Fab")
			(hide yes)
			(effects
				(font
					(size 1 1)
					(thickness 0.15)
				)
			)
		)
		(property "License" "Apache-2.0"
			(at 0 0 270)
			(unlocked yes)
			(layer "F.Fab")
			(hide yes)
			(effects
				(font
					(size 1 1)
					(thickness 0.15)
				)
			)
		)
		(property "Val" "10u"
			(at 0 0 270)
			(unlocked yes)
			(layer "F.Fab")
			(hide yes)
			(effects
				(font
					(size 1 1)
					(thickness 0.15)
				)
			)
		)
		(property "Voltage" ""
			(at 0 0 270)
			(unlocked yes)
			(layer "F.Fab")
			(hide yes)
			(effects
				(font
					(size 1 1)
					(thickness 0.15)
				)
			)
		)
		(property "Dielectric" ""
			(at 0 0 270)
			(unlocked yes)
			(layer "F.Fab")
			(hide yes)
			(effects
				(font
					(size 1 1)
					(thickness 0.15)
				)
			)
		)
		(property "Author" "Antmicro"
			(at 0 0 270)
			(unlocked yes)
			(layer "F.Fab")
			(hide yes)
			(effects
				(font
					(size 1 1)
					(thickness 0.15)
				)
			)
		)
		(sheetname "/TB Controller - Power/")
		(sheetfile "tb-power.kicad_sch")
		(attr smd)
		(fp_rect
			(start -0.925 -0.47)
			(end 0.925 0.47)
			(stroke
				(width 0.05)
				(type default)
			)
			(fill no)
			(layer "F.CrtYd")
		)
		(fp_line
			(start -0.494 0.248)
			(end -0.494 -0.25)
			(stroke
				(width 0.15)
				(type solid)
			)
			(layer "F.Fab")
		)
		(fp_line
			(start 0.504 0.248)
			(end -0.494 0.248)
			(stroke
				(width 0.15)
				(type solid)
			)
			(layer "F.Fab")
		)
		(fp_line
			(start -0.494 -0.25)
			(end 0.504 -0.25)
			(stroke
				(width 0.15)
				(type solid)
			)
			(layer "F.Fab")
		)
		(fp_line
			(start 0.504 -0.25)
			(end 0.504 0.248)
			(stroke
				(width 0.15)
				(type solid)
			)
			(layer "F.Fab")
		)
		(fp_text user "Author: Antmicro"
			(at -0.939 3.399 270)
			(layer "F.Fab")
			(effects
				(font
					(size 0.7 0.7)
					(thickness 0.15)
				)
				(justify left bottom)
			)
		)
		(fp_text user "${REFERENCE}"
			(at -0.939 4.599 270)
			(layer "F.Fab")
			(effects
				(font
					(size 0.7 0.7)
					(thickness 0.15)
				)
				(justify left bottom)
			)
		)
		(fp_text user "License: Apache-2.0"
			(at -0.939 5.799 270)
			(layer "F.Fab")
			(effects
				(font
					(size 0.7 0.7)
					(thickness 0.15)
				)
				(justify left bottom)
			)
		)
		(pad "1" smd roundrect
			(at -0.48 0 270)
			(size 0.59 0.64)
			(layers "F.Cu" "F.Mask" "F.Paste")
			(roundrect_rratio 0.25)
			(net 23 "GND")
			(pintype "passive")
		)
		(pad "2" smd roundrect
			(at 0.48 0 270)
			(size 0.59 0.64)
			(layers "F.Cu" "F.Mask" "F.Paste")
			(roundrect_rratio 0.25)
			(net 57 "+3V3_TB")
			(pintype "passive")
		)
	)
	(footprint "antmicro-footprints:C_0402_1005Metric"
		(layer "F.Cu")
		(at 134.249999 97.849998)
		(descr "Capacitor SMD 0402")
		(tags "capacitor SMD 0402")
		(property "Reference" "C124"
			(at 37.385 -9.199999 0)
			(layer "F.SilkS")
			(effects
				(font
					(size 0.7 0.7)
					(thickness 0.15)
				)
			)
		)
		(property "Value" "C_100n_0402"
			(at -1.022927 2.155213 0)
			(layer "F.Fab")
			(effects
				(font
					(size 0.7 0.7)
					(thickness 0.15)
				)
				(justify left bottom)
			)
		)
		(property "Datasheet" "https://www.murata.com/products/productdetail?partno=GRM155R61H104KE14%23"
			(at 0 0 0)
			(layer "F.Fab")
			(hide yes)
			(effects
				(font
					(size 1.27 1.27)
					(thickness 0.15)
				)
			)
		)
		(property "Description" "SMD Multilayer Ceramic Capacitor, 0.1 µF, 50 V, 0402 [1005 Metric], ± 10%, X5R, GRM Series"
			(at 0 0 0)
			(layer "F.Fab")
			(hide yes)
			(effects
				(font
					(size 1.27 1.27)
					(thickness 0.15)
				)
			)
		)
		(property "MPN" "GRM155R61H104KE14D"
			(at 0 0 0)
			(unlocked yes)
			(layer "F.Fab")
			(hide yes)
			(effects
				(font
					(size 1 1)
					(thickness 0.15)
				)
			)
		)
		(property "Manufacturer" "Murata"
			(at 0 0 0)
			(unlocked yes)
			(layer "F.Fab")
			(hide yes)
			(effects
				(font
					(size 1 1)
					(thickness 0.15)
				)
			)
		)
		(property "License" "Apache-2.0"
			(at 0 0 0)
			(unlocked yes)
			(layer "F.Fab")
			(hide yes)
			(effects
				(font
					(size 1 1)
					(thickness 0.15)
				)
			)
		)
		(property "Author" "Antmicro"
			(at 0 0 0)
			(unlocked yes)
			(layer "F.Fab")
			(hide yes)
			(effects
				(font
					(size 1 1)
					(thickness 0.15)
				)
			)
		)
		(property "Val" "100n"
			(at 0 0 0)
			(unlocked yes)
			(layer "F.Fab")
			(hide yes)
			(effects
				(font
					(size 1 1)
					(thickness 0.15)
				)
			)
		)
		(property "Voltage" "50V"
			(at 0 0 0)
			(unlocked yes)
			(layer "F.Fab")
			(hide yes)
			(effects
				(font
					(size 1 1)
					(thickness 0.15)
				)
			)
		)
		(property "Dielectric" "X5R"
			(at 0 0 0)
			(unlocked yes)
			(layer "F.Fab")
			(hide yes)
			(effects
				(font
					(size 1 1)
					(thickness 0.15)
				)
			)
		)
		(sheetname "/X710 DCDC converters/")
		(sheetfile "DCDC_converters_X710.kicad_sch")
		(attr smd)
		(fp_rect
			(start -0.925 -0.47)
			(end 0.925 0.47)
			(stroke
				(width 0.05)
				(type default)
			)
			(fill no)
			(layer "F.CrtYd")
		)
		(fp_line
			(start -0.494 -0.25)
			(end 0.504 -0.25)
			(stroke
				(width 0.15)
				(type solid)
			)
			(layer "F.Fab")
		)
		(fp_line
			(start -0.494 0.248)
			(end -0.494 -0.25)
			(stroke
				(width 0.15)
				(type solid)
			)
			(layer "F.Fab")
		)
		(fp_line
			(start 0.504 -0.25)
			(end 0.504 0.248)
			(stroke
				(width 0.15)
				(type solid)
			)
			(layer "F.Fab")
		)
		(fp_line
			(start 0.504 0.248)
			(end -0.494 0.248)
			(stroke
				(width 0.15)
				(type solid)
			)
			(layer "F.Fab")
		)
		(fp_text user "Author: Antmicro"
			(at -0.939 3.399 0)
			(layer "F.Fab")
			(effects
				(font
					(size 0.7 0.7)
					(thickness 0.15)
				)
				(justify left bottom)
			)
		)
		(fp_text user "${REFERENCE}"
			(at -0.939 4.599 0)
			(layer "F.Fab")
			(effects
				(font
					(size 0.7 0.7)
					(thickness 0.15)
				)
				(justify left bottom)
			)
		)
		(fp_text user "License: Apache-2.0"
			(at -0.939 5.799 0)
			(layer "F.Fab")
			(effects
				(font
					(size 0.7 0.7)
					(thickness 0.15)
				)
				(justify left bottom)
			)
		)
		(pad "1" smd roundrect
			(at -0.48 0)
			(size 0.59 0.64)
			(layers "F.Cu" "F.Mask" "F.Paste")
			(roundrect_rratio 0.25)
			(net 118 "/X710 DCDC converters/3V3_BST")
			(pintype "passive")
		)
		(pad "2" smd roundrect
			(at 0.48 0)
			(size 0.59 0.64)
			(layers "F.Cu" "F.Mask" "F.Paste")
			(roundrect_rratio 0.25)
			(net 117 "/X710 DCDC converters/3V3_SW")
			(pintype "passive")
		)
	)
	(footprint "antmicro-footprints:C_0603_1608Metric_EIA"
		(layer "F.Cu")
		(at 134.655 89.274999 -90)
		(descr "Capacitor SMD 0603, IPC-7351 Density Level A")
		(tags "Capacitor 0603")
		(property "Reference" "C254"
			(at 4.225001 16.405 270)
			(layer "F.SilkS")
			(effects
				(font
					(size 0.7 0.7)
					(thickness 0.15)
				)
				(justify left bottom)
			)
		)
		(property "Value" "C_22u_16V_0603"
			(at -1.42757 1.770288 270)
			(layer "F.Fab")
			(effects
				(font
					(size 0.7 0.7)
					(thickness 0.15)
				)
				(justify left bottom)
			)
		)
		(property "Datasheet" "https://product.samsungsem.com/mlcc/CL10A226MO7JZN.do"
			(at 0 0 270)
			(layer "F.Fab")
			(hide yes)
			(effects
				(font
					(size 1.27 1.27)
					(thickness 0.15)
				)
			)
		)
		(property "Description" "SMD Multilayer Ceramic Capacitor"
			(at 0 0 270)
			(layer "F.Fab")
			(hide yes)
			(effects
				(font
					(size 1.27 1.27)
					(thickness 0.15)
				)
			)
		)
		(property "MPN" "CL10A226MO7JZNC"
			(at 0 0 270)
			(unlocked yes)
			(layer "F.Fab")
			(hide yes)
			(effects
				(font
					(size 1 1)
					(thickness 0.15)
				)
			)
		)
		(property "Manufacturer" "Samsung Electro-Mechanics"
			(at 0 0 270)
			(unlocked yes)
			(layer "F.Fab")
			(hide yes)
			(effects
				(font
					(size 1 1)
					(thickness 0.15)
				)
			)
		)
		(property "License" "Apache-2.0"
			(at 0 0 270)
			(unlocked yes)
			(layer "F.Fab")
			(hide yes)
			(effects
				(font
					(size 1 1)
					(thickness 0.15)
				)
			)
		)
		(property "Author" "Antmicro"
			(at 0 0 270)
			(unlocked yes)
			(layer "F.Fab")
			(hide yes)
			(effects
				(font
					(size 1 1)
					(thickness 0.15)
				)
			)
		)
		(property "Val" "22u"
			(at 0 0 270)
			(unlocked yes)
			(layer "F.Fab")
			(hide yes)
			(effects
				(font
					(size 1 1)
					(thickness 0.15)
				)
			)
		)
		(property "Voltage" "16V"
			(at 0 0 270)
			(unlocked yes)
			(layer "F.Fab")
			(hide yes)
			(effects
				(font
					(size 1 1)
					(thickness 0.15)
				)
			)
		)
		(property "Dielectric" ""
			(at 0 0 270)
			(unlocked yes)
			(layer "F.Fab")
			(hide yes)
			(effects
				(font
					(size 1 1)
					(thickness 0.15)
				)
			)
		)
		(sheetname "/X710-AT2 power/")
		(sheetfile "x710-at2-power.kicad_sch")
		(attr smd)
		(fp_line
			(start -0.15 0.55)
			(end 0.15 0.55)
			(stroke
				(width 0.15)
				(type solid)
			)
			(layer "F.SilkS")
		)
		(fp_line
			(start -0.15 -0.55)
			(end 0.15 -0.55)
			(stroke
				(width 0.15)
				(type solid)
			)
			(layer "F.SilkS")
		)
		(fp_rect
			(start -1.25 -0.65)
			(end 1.25 0.65)
			(stroke
				(width 0.05)
				(type solid)
			)
			(fill no)
			(layer "F.CrtYd")
		)
		(fp_rect
			(start -0.8 -0.45)
			(end 0.8 0.45)
			(stroke
				(width 0.15)
				(type solid)
			)
			(fill no)
			(layer "F.Fab")
		)
		(fp_text user "License: Apache-2.0"
			(at -1.682 5.895 270)
			(layer "F.Fab")
			(effects
				(font
					(size 0.7 0.7)
					(thickness 0.15)
				)
				(justify left bottom)
			)
		)
		(fp_text user "Author: Antmicro"
			(at -1.682 4.894 270)
			(layer "F.Fab")
			(effects
				(font
					(size 0.7 0.7)
					(thickness 0.15)
				)
				(justify left bottom)
			)
		)
		(fp_text user "${REFERENCE}"
			(at -1.682 3.895 270)
			(layer "F.Fab")
			(effects
				(font
					(size 0.7 0.7)
					(thickness 0.15)
				)
				(justify left bottom)
			)
		)
		(pad "1" smd roundrect
			(at -0.7 0 270)
			(size 0.8 1.1)
			(layers "F.Cu" "F.Mask" "F.Paste")
			(roundrect_rratio 0.2)
			(net 23 "GND")
			(pintype "passive")
		)
		(pad "2" smd roundrect
			(at 0.7 0 270)
			(size 0.8 1.1)
			(layers "F.Cu" "F.Mask" "F.Paste")
			(roundrect_rratio 0.2)
			(net 7 "+3V3")
			(pintype "passive")
		)
	)
)
